(kicad_pcb
	(version 20260206)
	(generator "pcbnew")
	(generator_version "10.0")
	(general
		(thickness 1.6)
		(legacy_teardrops no)
	)
	(paper "A4")
	(title_block
		(title "12092022_DA0F0TMDCD0_F0T_Management_Board_D_brd_V3_OCP.brd")
		(comment 1 "Grand Teton / footprints 1058-1063 of 1440")
	)
	(layers
		(0 "F.Cu" signal "TOP")
		(4 "In1.Cu" signal "GND")
		(6 "In2.Cu" signal "IN1")
		(8 "In3.Cu" signal "GND1")
		(10 "In4.Cu" signal "IN2")
		(12 "In5.Cu" signal "VCC")
		(14 "In6.Cu" signal "VCC1")
		(16 "In7.Cu" signal "IN3")
		(18 "In8.Cu" signal "GND2")
		(20 "In9.Cu" signal "IN4")
		(22 "In10.Cu" signal "GND3")
		(2 "B.Cu" signal "BOTTOM")
		(9 "F.Adhes" user "F.Adhesive")
		(11 "B.Adhes" user "B.Adhesive")
		(13 "F.Paste" user "Package Geometry/Pastemask Top")
		(15 "B.Paste" user "Package Geometry/Pastemask Bottom")
		(5 "F.SilkS" user "Ref Des/Silkscreen Top")
		(7 "B.SilkS" user "Ref Des/Silkscreen Bottom")
		(1 "F.Mask" user "Board Geometry/Soldermask Top")
		(3 "B.Mask" user "Board Geometry/Soldermask Bottom")
		(17 "Dwgs.User" user "User.Drawings")
		(19 "Cmts.User" user "User.Comments")
		(21 "Eco1.User" user "User.Eco1")
		(23 "Eco2.User" user "User.Eco2")
		(25 "Edge.Cuts" user "Board Geometry/Outline")
		(27 "Margin" user)
		(31 "F.CrtYd" user "Package Geometry/Place Bound Top")
		(29 "B.CrtYd" user "Package Geometry/Place Bound Bottom")
		(35 "F.Fab" user "Ref Des/Assembly Top")
		(33 "B.Fab" user "Ref Des/Assembly Bottom")
	)
	(footprint ""
		(layer "B.Cu")
		(at 103.8225 -104.76484 90)
		(property "Reference" "J17"
			(at -0.87884 2.95783 270)
			(unlocked yes)
			(layer "B.SilkS")
			(effects
				(font
					(size 0.7874 0.5842)
					(thickness 0.1524)
				)
				(justify left mirror)
			)
		)
		(property "Value" ""
			(at 0 0 90)
			(layer "B.Fab")
			(effects
				(font
					(size 1.27 1.27)
				)
				(justify mirror)
			)
		)
		(duplicate_pad_numbers_are_jumpers no)
		(fp_line
			(start 1.2192 -2.1082)
			(end -1.2192 -2.1082)
			(stroke
				(width 0.1524)
				(type default)
			)
			(layer "B.SilkS")
		)
		(fp_line
			(start -1.2192 -2.1082)
			(end -1.2192 -0.456184)
			(stroke
				(width 0.1524)
				(type default)
			)
			(layer "B.SilkS")
		)
		(fp_line
			(start -1.2192 0.451104)
			(end -1.2192 2.1082)
			(stroke
				(width 0.1524)
				(type default)
			)
			(layer "B.SilkS")
		)
		(fp_line
			(start 1.2192 2.1082)
			(end 1.2192 -2.1082)
			(stroke
				(width 0.1524)
				(type default)
			)
			(layer "B.SilkS")
		)
		(fp_line
			(start -1.2192 2.1082)
			(end 1.2192 2.1082)
			(stroke
				(width 0.1524)
				(type default)
			)
			(layer "B.SilkS")
		)
		(pad "" np_thru_hole circle
			(at -3.4671 -1.27)
			(size 1.0414 1.0414)
			(drill 1.0414)
			(layers "*.Cu" "*.Mask")
			(clearance 0.381)
			(thermal_gap 0.381)
		)
		(pad "" np_thru_hole circle
			(at -3.4671 1.27)
			(size 1.0414 1.0414)
			(drill 1.0414)
			(layers "*.Cu" "*.Mask")
			(clearance 0.381)
			(thermal_gap 0.381)
		)
		(pad "" np_thru_hole circle
			(at 2.8829 -1.27)
			(size 1.0414 1.0414)
			(drill 1.0414)
			(layers "*.Cu" "*.Mask")
			(clearance 0.381)
			(thermal_gap 0.381)
		)
		(pad "" np_thru_hole circle
			(at 2.8829 1.27)
			(size 1.0414 1.0414)
			(drill 1.0414)
			(layers "*.Cu" "*.Mask")
			(clearance 0.381)
			(thermal_gap 0.381)
		)
		(pad "1" smd rect
			(at -0.8255 -0.249936)
			(size 0.3048 0.508)
			(layers "B.Cu" "B.Mask" "B.Paste")
			(net "85_5INCH_BOT_DN")
		)
		(pad "2" smd rect
			(at -0.8255 0.249936)
			(size 0.3048 0.508)
			(layers "B.Cu" "B.Mask" "B.Paste")
			(net "85_5INCH_BOT_DP")
		)
		(pad "3" smd circle
			(at 0 0 270)
			(size 0 0)
			(layers "B.Cu" "B.Mask" "B.Paste")
			(net "GND_P1")
		)
		(zone
			(layers "F.Cu" "B.Cu" "In1.Cu" "In2.Cu" "In3.Cu" "In4.Cu" "In5.Cu" "In6.Cu"
				"In7.Cu" "In8.Cu" "In9.Cu" "In10.Cu"
			)
			(hatch none 0.5)
			(connect_pads
				(clearance 0)
			)
			(min_thickness 0.25)
			(keepout
				(tracks not_allowed)
				(vias allowed)
				(pads allowed)
				(copperpour not_allowed)
				(footprints allowed)
			)
			(placement
				(enabled no)
				(sheetname "")
			)
			(fill
				(thermal_gap 0.5)
				(thermal_bridge_width 0.5)
				(island_removal_mode 0)
			)
			(polygon
				(pts
					(arc
						(start 103.4796 -107.64774)
						(mid 101.6254 -107.64774)
						(end 103.4796 -107.64774)
					)
				)
			)
		)
		(zone
			(layers "F.Cu" "B.Cu" "In1.Cu" "In2.Cu" "In3.Cu" "In4.Cu" "In5.Cu" "In6.Cu"
				"In7.Cu" "In8.Cu" "In9.Cu" "In10.Cu"
			)
			(hatch none 0.5)
			(connect_pads
				(clearance 0)
			)
			(min_thickness 0.25)
			(keepout
				(tracks not_allowed)
				(vias allowed)
				(pads allowed)
				(copperpour not_allowed)
				(footprints allowed)
			)
			(placement
				(enabled no)
				(sheetname "")
			)
			(fill
				(thermal_gap 0.5)
				(thermal_bridge_width 0.5)
				(island_removal_mode 0)
			)
			(polygon
				(pts
					(arc
						(start 103.4796 -101.29774)
						(mid 101.6254 -101.29774)
						(end 103.4796 -101.29774)
					)
				)
			)
		)
		(zone
			(layers "F.Cu" "B.Cu" "In1.Cu" "In2.Cu" "In3.Cu" "In4.Cu" "In5.Cu" "In6.Cu"
				"In7.Cu" "In8.Cu" "In9.Cu" "In10.Cu"
			)
			(hatch none 0.5)
			(connect_pads
				(clearance 0)
			)
			(min_thickness 0.25)
			(keepout
				(tracks not_allowed)
				(vias allowed)
				(pads allowed)
				(copperpour not_allowed)
				(footprints allowed)
			)
			(placement
				(enabled no)
				(sheetname "")
			)
			(fill
				(thermal_gap 0.5)
				(thermal_bridge_width 0.5)
				(island_removal_mode 0)
			)
			(polygon
				(pts
					(arc
						(start 106.0196 -107.64774)
						(mid 104.1654 -107.64774)
						(end 106.0196 -107.64774)
					)
				)
			)
		)
		(zone
			(layers "F.Cu" "B.Cu" "In1.Cu" "In2.Cu" "In3.Cu" "In4.Cu" "In5.Cu" "In6.Cu"
				"In7.Cu" "In8.Cu" "In9.Cu" "In10.Cu"
			)
			(hatch none 0.5)
			(connect_pads
				(clearance 0)
			)
			(min_thickness 0.25)
			(keepout
				(tracks not_allowed)
				(vias allowed)
				(pads allowed)
				(copperpour not_allowed)
				(footprints allowed)
			)
			(placement
				(enabled no)
				(sheetname "")
			)
			(fill
				(thermal_gap 0.5)
				(thermal_bridge_width 0.5)
				(island_removal_mode 0)
			)
			(polygon
				(pts
					(arc
						(start 106.0196 -101.29774)
						(mid 104.1654 -101.29774)
						(end 106.0196 -101.29774)
					)
				)
			)
		)
		(zone
			(layer "B.Cu")
			(hatch none 0.5)
			(connect_pads
				(clearance 0)
			)
			(min_thickness 0.25)
			(keepout
				(tracks not_allowed)
				(vias allowed)
				(pads allowed)
				(copperpour not_allowed)
				(footprints allowed)
			)
			(placement
				(enabled no)
				(sheetname "")
			)
			(fill
				(thermal_gap 0.5)
				(thermal_bridge_width 0.5)
				(island_removal_mode 0)
			)
			(polygon
				(pts
					(xy 103.27386 -103.64724) (xy 103.369364 -103.64724) (xy 103.369364 -104.24414) (xy 103.775764 -104.24414)
					(xy 103.775764 -103.64724) (xy 103.869236 -103.64724) (xy 103.869236 -104.24414) (xy 104.275636 -104.24414)
					(xy 104.275636 -103.64724) (xy 104.37114 -103.64724) (xy 104.37114 -104.34574) (xy 103.27386 -104.34574)
				)
			)
		)
	)
	(footprint ""
		(layer "B.Cu")
		(at 51.255422 -45.204126 180)
		(property "Reference" "C39"
			(at 0 0 0)
			(layer "B.SilkS")
			(hide yes)
			(effects
				(font
					(size 1.27 1.27)
				)
				(justify mirror)
			)
		)
		(property "Value" ""
			(at 0 0 0)
			(layer "B.Fab")
			(effects
				(font
					(size 1.27 1.27)
				)
				(justify mirror)
			)
		)
		(duplicate_pad_numbers_are_jumpers no)
		(fp_line
			(start 0.7874 0.4064)
			(end 0.7874 -0.4064)
			(stroke
				(width 0.1524)
				(type default)
			)
			(layer "B.SilkS")
		)
		(fp_line
			(start 0.7874 -0.4064)
			(end -0.7874 -0.4064)
			(stroke
				(width 0.1524)
				(type default)
			)
			(layer "B.SilkS")
		)
		(fp_line
			(start -0.7874 0.4064)
			(end 0.7874 0.4064)
			(stroke
				(width 0.1524)
				(type default)
			)
			(layer "B.SilkS")
		)
		(fp_line
			(start -0.7874 -0.4064)
			(end -0.7874 0.4064)
			(stroke
				(width 0.1524)
				(type default)
			)
			(layer "B.SilkS")
		)
		(fp_line
			(start 0.67945 0.3048)
			(end 0.67945 -0.305054)
			(stroke
				(width 0.1)
				(type default)
			)
			(layer "B.Fab")
		)
		(fp_line
			(start 0.67945 -0.305054)
			(end 0.12065 -0.305054)
			(stroke
				(width 0.1)
				(type default)
			)
			(layer "B.Fab")
		)
		(fp_line
			(start 0.12065 0.3048)
			(end 0.67945 0.3048)
			(stroke
				(width 0.1)
				(type default)
			)
			(layer "B.Fab")
		)
		(fp_line
			(start 0.12065 0.2794)
			(end 0.12065 0.3048)
			(stroke
				(width 0.1)
				(type default)
			)
			(layer "B.Fab")
		)
		(fp_line
			(start 0.12065 -0.2794)
			(end -0.12065 -0.2794)
			(stroke
				(width 0.1)
				(type default)
			)
			(layer "B.Fab")
		)
		(fp_line
			(start 0.12065 -0.305054)
			(end 0.12065 -0.2794)
			(stroke
				(width 0.1)
				(type default)
			)
			(layer "B.Fab")
		)
		(fp_line
			(start -0.120396 0.3048)
			(end -0.120396 0.2794)
			(stroke
				(width 0.1)
				(type default)
			)
			(layer "B.Fab")
		)
		(fp_line
			(start -0.120396 0.2794)
			(end 0.12065 0.2794)
			(stroke
				(width 0.1)
				(type default)
			)
			(layer "B.Fab")
		)
		(fp_line
			(start -0.12065 -0.2794)
			(end -0.12065 -0.3048)
			(stroke
				(width 0.1)
				(type default)
			)
			(layer "B.Fab")
		)
		(fp_line
			(start -0.12065 -0.3048)
			(end -0.67945 -0.3048)
			(stroke
				(width 0.1)
				(type default)
			)
			(layer "B.Fab")
		)
		(fp_line
			(start -0.67945 0.3048)
			(end -0.120396 0.3048)
			(stroke
				(width 0.1)
				(type default)
			)
			(layer "B.Fab")
		)
		(fp_line
			(start -0.67945 -0.3048)
			(end -0.67945 0.3048)
			(stroke
				(width 0.1)
				(type default)
			)
			(layer "B.Fab")
		)
		(pad "1" smd circle
			(at 0.40005 0)
			(size 0 0)
			(layers "B.Cu" "B.Mask" "B.Paste")
			(net "P3V3_P1V8_SD2VDD")
		)
		(pad "2" smd circle
			(at -0.40005 0)
			(size 0 0)
			(layers "B.Cu" "B.Mask" "B.Paste")
			(net "GND")
		)
	)
	(footprint ""
		(layer "B.Cu")
		(at 77.47 -31.115 90)
		(property "Reference" "R676"
			(at 0 0 90)
			(layer "B.SilkS")
			(hide yes)
			(effects
				(font
					(size 1.27 1.27)
				)
				(justify mirror)
			)
		)
		(property "Value" ""
			(at 0 0 90)
			(layer "B.Fab")
			(effects
				(font
					(size 1.27 1.27)
				)
				(justify mirror)
			)
		)
		(duplicate_pad_numbers_are_jumpers no)
		(fp_line
			(start 0.7874 -0.4064)
			(end -0.7874 -0.4064)
			(stroke
				(width 0.1524)
				(type default)
			)
			(layer "B.SilkS")
		)
		(fp_line
			(start -0.7874 -0.4064)
			(end -0.7874 0.4064)
			(stroke
				(width 0.1524)
				(type default)
			)
			(layer "B.SilkS")
		)
		(fp_line
			(start 0.7874 0.4064)
			(end 0.7874 -0.4064)
			(stroke
				(width 0.1524)
				(type default)
			)
			(layer "B.SilkS")
		)
		(fp_line
			(start -0.7874 0.4064)
			(end 0.7874 0.4064)
			(stroke
				(width 0.1524)
				(type default)
			)
			(layer "B.SilkS")
		)
		(fp_line
			(start 0.67945 -0.305054)
			(end 0.12065 -0.305054)
			(stroke
				(width 0.1)
				(type default)
			)
			(layer "B.Fab")
		)
		(fp_line
			(start 0.12065 -0.305054)
			(end 0.12065 -0.2794)
			(stroke
				(width 0.1)
				(type default)
			)
			(layer "B.Fab")
		)
		(fp_line
			(start -0.12065 -0.3048)
			(end -0.67945 -0.3048)
			(stroke
				(width 0.1)
				(type default)
			)
			(layer "B.Fab")
		)
		(fp_line
			(start -0.67945 -0.3048)
			(end -0.67945 0.3048)
			(stroke
				(width 0.1)
				(type default)
			)
			(layer "B.Fab")
		)
		(fp_line
			(start 0.12065 -0.2794)
			(end -0.12065 -0.2794)
			(stroke
				(width 0.1)
				(type default)
			)
			(layer "B.Fab")
		)
		(fp_line
			(start -0.12065 -0.2794)
			(end -0.12065 -0.3048)
			(stroke
				(width 0.1)
				(type default)
			)
			(layer "B.Fab")
		)
		(fp_line
			(start 0.12065 0.2794)
			(end 0.12065 0.3048)
			(stroke
				(width 0.1)
				(type default)
			)
			(layer "B.Fab")
		)
		(fp_line
			(start -0.120396 0.2794)
			(end 0.12065 0.2794)
			(stroke
				(width 0.1)
				(type default)
			)
			(layer "B.Fab")
		)
		(fp_line
			(start 0.67945 0.3048)
			(end 0.67945 -0.305054)
			(stroke
				(width 0.1)
				(type default)
			)
			(layer "B.Fab")
		)
		(fp_line
			(start 0.12065 0.3048)
			(end 0.67945 0.3048)
			(stroke
				(width 0.1)
				(type default)
			)
			(layer "B.Fab")
		)
		(fp_line
			(start -0.120396 0.3048)
			(end -0.120396 0.2794)
			(stroke
				(width 0.1)
				(type default)
			)
			(layer "B.Fab")
		)
		(fp_line
			(start -0.67945 0.3048)
			(end -0.120396 0.3048)
			(stroke
				(width 0.1)
				(type default)
			)
			(layer "B.Fab")
		)
		(pad "1" smd circle
			(at 0.40005 0 270)
			(size 0 0)
			(layers "B.Cu" "B.Mask" "B.Paste")
			(net "LED_POSTCODE_5")
		)
		(pad "2" smd circle
			(at -0.40005 0 270)
			(size 0 0)
			(layers "B.Cu" "B.Mask" "B.Paste")
			(net "LED_POSTCODE_5_R1")
		)
	)
	(footprint ""
		(layer "B.Cu")
		(at 26.533094 -19.955764 180)
		(property "Reference" "R86"
			(at 0 0 0)
			(layer "B.SilkS")
			(hide yes)
			(effects
				(font
					(size 1.27 1.27)
				)
				(justify mirror)
			)
		)
		(property "Value" ""
			(at 0 0 0)
			(layer "B.Fab")
			(effects
				(font
					(size 1.27 1.27)
				)
				(justify mirror)
			)
		)
		(duplicate_pad_numbers_are_jumpers no)
		(fp_line
			(start 0.7874 0.4064)
			(end 0.7874 -0.4064)
			(stroke
				(width 0.1524)
				(type default)
			)
			(layer "B.SilkS")
		)
		(fp_line
			(start 0.7874 -0.4064)
			(end -0.7874 -0.4064)
			(stroke
				(width 0.1524)
				(type default)
			)
			(layer "B.SilkS")
		)
		(fp_line
			(start -0.7874 0.4064)
			(end 0.7874 0.4064)
			(stroke
				(width 0.1524)
				(type default)
			)
			(layer "B.SilkS")
		)
		(fp_line
			(start -0.7874 -0.4064)
			(end -0.7874 0.4064)
			(stroke
				(width 0.1524)
				(type default)
			)
			(layer "B.SilkS")
		)
		(fp_line
			(start 0.67945 0.3048)
			(end 0.67945 -0.305054)
			(stroke
				(width 0.1)
				(type default)
			)
			(layer "B.Fab")
		)
		(fp_line
			(start 0.67945 -0.305054)
			(end 0.12065 -0.305054)
			(stroke
				(width 0.1)
				(type default)
			)
			(layer "B.Fab")
		)
		(fp_line
			(start 0.12065 0.3048)
			(end 0.67945 0.3048)
			(stroke
				(width 0.1)
				(type default)
			)
			(layer "B.Fab")
		)
		(fp_line
			(start 0.12065 0.2794)
			(end 0.12065 0.3048)
			(stroke
				(width 0.1)
				(type default)
			)
			(layer "B.Fab")
		)
		(fp_line
			(start 0.12065 -0.2794)
			(end -0.12065 -0.2794)
			(stroke
				(width 0.1)
				(type default)
			)
			(layer "B.Fab")
		)
		(fp_line
			(start 0.12065 -0.305054)
			(end 0.12065 -0.2794)
			(stroke
				(width 0.1)
				(type default)
			)
			(layer "B.Fab")
		)
		(fp_line
			(start -0.120396 0.3048)
			(end -0.120396 0.2794)
			(stroke
				(width 0.1)
				(type default)
			)
			(layer "B.Fab")
		)
		(fp_line
			(start -0.120396 0.2794)
			(end 0.12065 0.2794)
			(stroke
				(width 0.1)
				(type default)
			)
			(layer "B.Fab")
		)
		(fp_line
			(start -0.12065 -0.2794)
			(end -0.12065 -0.3048)
			(stroke
				(width 0.1)
				(type default)
			)
			(layer "B.Fab")
		)
		(fp_line
			(start -0.12065 -0.3048)
			(end -0.67945 -0.3048)
			(stroke
				(width 0.1)
				(type default)
			)
			(layer "B.Fab")
		)
		(fp_line
			(start -0.67945 0.3048)
			(end -0.120396 0.3048)
			(stroke
				(width 0.1)
				(type default)
			)
			(layer "B.Fab")
		)
		(fp_line
			(start -0.67945 -0.3048)
			(end -0.67945 0.3048)
			(stroke
				(width 0.1)
				(type default)
			)
			(layer "B.Fab")
		)
		(pad "1" smd circle
			(at 0.40005 0)
			(size 0 0)
			(layers "B.Cu" "B.Mask" "B.Paste")
			(net "P3V3_RGM")
		)
		(pad "2" smd circle
			(at -0.40005 0)
			(size 0 0)
			(layers "B.Cu" "B.Mask" "B.Paste")
			(net "V_BMC_DDC_LS_GATE")
		)
	)
	(footprint ""
		(layer "B.Cu")
		(at 11.098022 -67.644264)
		(property "Reference" "ME4"
			(at 0 0 0)
			(layer "B.SilkS")
			(hide yes)
			(effects
				(font
					(size 1.27 1.27)
				)
				(justify mirror)
			)
		)
		(property "Value" ""
			(at 0 0 0)
			(layer "B.Fab")
			(effects
				(font
					(size 1.27 1.27)
				)
				(justify mirror)
			)
		)
		(duplicate_pad_numbers_are_jumpers no)
		(fp_line
			(start -6.999986 -6.999986)
			(end -6.999986 -5.475986)
			(stroke
				(width 0.1524)
				(type default)
			)
			(layer "B.SilkS")
		)
		(fp_line
			(start -6.999986 -1.524)
			(end -6.999986 0)
			(stroke
				(width 0.1524)
				(type default)
			)
			(layer "B.SilkS")
		)
		(fp_line
			(start -6.999986 0)
			(end -5.475986 0)
			(stroke
				(width 0.1524)
				(type default)
			)
			(layer "B.SilkS")
		)
		(fp_line
			(start -5.475986 -6.999986)
			(end -6.999986 -6.999986)
			(stroke
				(width 0.1524)
				(type default)
			)
			(layer "B.SilkS")
		)
		(fp_line
			(start -1.524 -6.999986)
			(end 0 -6.999986)
			(stroke
				(width 0.1524)
				(type default)
			)
			(layer "B.SilkS")
		)
		(fp_line
			(start 0 -6.999986)
			(end 0 -5.475986)
			(stroke
				(width 0.1524)
				(type default)
			)
			(layer "B.SilkS")
		)
		(fp_line
			(start 0 -1.524)
			(end 0 0)
			(stroke
				(width 0.1524)
				(type default)
			)
			(layer "B.SilkS")
		)
		(fp_line
			(start 0 0)
			(end -1.524 0)
			(stroke
				(width 0.1524)
				(type default)
			)
			(layer "B.SilkS")
		)
		(fp_text user "S/N"
			(at -0.361188 -5.450078 0)
			(unlocked yes)
			(layer "B.SilkS")
			(effects
				(font
					(size 1.905 1.4224)
					(thickness 0.1524)
				)
				(justify left mirror)
			)
		)
	)
	(footprint ""
		(layer "B.Cu")
		(at 14.982444 -99.194112 135)
		(property "Reference" "C193"
			(at 0 0 135)
			(layer "B.SilkS")
			(hide yes)
			(effects
				(font
					(size 1.27 1.27)
				)
				(justify mirror)
			)
		)
		(property "Value" ""
			(at 0 0 135)
			(layer "B.Fab")
			(effects
				(font
					(size 1.27 1.27)
				)
				(justify mirror)
			)
		)
		(duplicate_pad_numbers_are_jumpers no)
		(fp_line
			(start 0.787389 -0.406267)
			(end -0.787389 -0.406267)
			(stroke
				(width 0.1524)
				(type default)
			)
			(layer "B.SilkS")
		)
		(fp_line
			(start 0.787389 0.406267)
			(end 0.787389 -0.406267)
			(stroke
				(width 0.1524)
				(type default)
			)
			(layer "B.SilkS")
		)
		(fp_line
			(start -0.787389 -0.406267)
			(end -0.787389 0.406267)
			(stroke
				(width 0.1524)
				(type default)
			)
			(layer "B.SilkS")
		)
		(fp_line
			(start -0.787389 0.406267)
			(end 0.787389 0.406267)
			(stroke
				(width 0.1524)
				(type default)
			)
			(layer "B.SilkS")
		)
		(fp_line
			(start 0.679446 -0.305149)
			(end 0.120695 -0.304969)
			(stroke
				(width 0.1)
				(type default)
			)
			(layer "B.Fab")
		)
		(fp_line
			(start 0.120695 -0.304969)
			(end 0.120695 -0.279466)
			(stroke
				(width 0.1)
				(type default)
			)
			(layer "B.Fab")
		)
		(fp_line
			(start 0.120695 -0.279466)
			(end -0.120695 -0.279466)
			(stroke
				(width 0.1)
				(type default)
			)
			(layer "B.Fab")
		)
		(fp_line
			(start 0.679446 0.30479)
			(end 0.679446 -0.305149)
			(stroke
				(width 0.1)
				(type default)
			)
			(layer "B.Fab")
		)
		(fp_line
			(start -0.120515 -0.30479)
			(end -0.679446 -0.30479)
			(stroke
				(width 0.1)
				(type default)
			)
			(layer "B.Fab")
		)
		(fp_line
			(start -0.120695 -0.279466)
			(end -0.120515 -0.30479)
			(stroke
				(width 0.1)
				(type default)
			)
			(layer "B.Fab")
		)
		(fp_line
			(start 0.120695 0.279466)
			(end 0.120515 0.30479)
			(stroke
				(width 0.1)
				(type default)
			)
			(layer "B.Fab")
		)
		(fp_line
			(start 0.120515 0.30479)
			(end 0.679446 0.30479)
			(stroke
				(width 0.1)
				(type default)
			)
			(layer "B.Fab")
		)
		(fp_line
			(start -0.679446 -0.30479)
			(end -0.679446 0.30479)
			(stroke
				(width 0.1)
				(type default)
			)
			(layer "B.Fab")
		)
		(fp_line
			(start -0.120335 0.279466)
			(end 0.120695 0.279466)
			(stroke
				(width 0.1)
				(type default)
			)
			(layer "B.Fab")
		)
		(fp_line
			(start -0.120515 0.30479)
			(end -0.120335 0.279466)
			(stroke
				(width 0.1)
				(type default)
			)
			(layer "B.Fab")
		)
		(fp_line
			(start -0.679446 0.30479)
			(end -0.120515 0.30479)
			(stroke
				(width 0.1)
				(type default)
			)
			(layer "B.Fab")
		)
		(pad "1" smd circle
			(at 0.40005 0 315)
			(size 0 0)
			(layers "B.Cu" "B.Mask" "B.Paste")
			(net "PVCCA_AUX_PLD")
		)
		(pad "2" smd circle
			(at -0.40005 0 315)
			(size 0 0)
			(layers "B.Cu" "B.Mask" "B.Paste")
			(net "GND")
		)
	)
)
